(kicad_pcb
	(version 20260206)
	(generator "pcbnew")
	(generator_version "10.0")
	(general
		(thickness 1.6)
		(legacy_teardrops no)
	)
	(paper "A4")
	(title_block
		(title "Wiwynn_Tioga_Pass_MB.brd")
		(comment 1 "Tioga Pass / footprint 190 of 4770 (U2D1), pads 3370-3482 of 3647")
	)
	(layers
		(0 "F.Cu" signal "TOP")
		(4 "In1.Cu" signal "L2GND")
		(6 "In2.Cu" signal "L3")
		(8 "In3.Cu" signal "L4GND")
		(10 "In4.Cu" signal "L5")
		(12 "In5.Cu" signal "L6GND")
		(14 "In6.Cu" signal "L7VCC")
		(16 "In7.Cu" signal "L8VCC")
		(18 "In8.Cu" signal "L9GND")
		(20 "In9.Cu" signal "L10")
		(22 "In10.Cu" signal "L11GND")
		(24 "In11.Cu" signal "L12")
		(26 "In12.Cu" signal "L13GND")
		(2 "B.Cu" signal "BOTTOM")
		(9 "F.Adhes" user "F.Adhesive")
		(11 "B.Adhes" user "B.Adhesive")
		(13 "F.Paste" user "Package Geometry/Pastemask Top")
		(15 "B.Paste" user "Package Geometry/Pastemask Bottom")
		(5 "F.SilkS" user "Ref Des/Silkscreen Top")
		(7 "B.SilkS" user "Ref Des/Silkscreen Bottom")
		(1 "F.Mask" user "Board Geometry/Soldermask Top")
		(3 "B.Mask" user "Board Geometry/Soldermask Bottom")
		(17 "Dwgs.User" user "User.Drawings")
		(19 "Cmts.User" user "User.Comments")
		(21 "Eco1.User" user "User.Eco1")
		(23 "Eco2.User" user "User.Eco2")
		(25 "Edge.Cuts" user "Board Geometry/Outline")
		(27 "Margin" user)
		(31 "F.CrtYd" user "Package Geometry/Place Bound Top")
		(29 "B.CrtYd" user "Package Geometry/Place Bound Bottom")
		(35 "F.Fab" user "Ref Des/Assembly Top")
		(33 "B.Fab" user "Ref Des/Assembly Bottom")
	)
	(footprint ""
		(layer "F.Cu")
		(at 104.99979 -76.550012 180)
		(property "Reference" "U2D1"
			(at 25.19299 30.484318 0)
			(unlocked yes)
			(layer "F.SilkS")
			(effects
				(font
					(size 0.7874 0.5842)
					(thickness 0.1524)
				)
			)
		)
		(property "Value" ""
			(at 0 0 180)
			(layer "F.Fab")
			(effects
				(font
					(size 1.27 1.27)
				)
			)
		)
		(duplicate_pad_numbers_are_jumpers no)
		(pad "P41" smd circle
			(at -2.910586 -18.664428)
			(size 0.4318 0.4318)
			(layers "F.Cu" "F.Mask" "F.Paste")
			(net "M_H_DQ<39>")
		)
		(pad "P43" smd circle
			(at -1.193546 -18.664428)
			(size 0.4318 0.4318)
			(layers "F.Cu" "F.Mask" "F.Paste")
			(net "M_H_DQ<36>")
		)
		(pad "P45" smd circle
			(at 2.052066 -20.464526)
			(size 0.508 0.508)
			(layers "F.Cu" "F.Mask" "F.Paste")
			(net "GND")
		)
		(pad "P47" smd circle
			(at 3.769106 -20.464526)
			(size 0.4318 0.4318)
			(layers "F.Cu" "F.Mask" "F.Paste")
			(net "GND")
		)
		(pad "P49" smd circle
			(at 5.485892 -20.464526)
			(size 0.4318 0.4318)
			(layers "F.Cu" "F.Mask" "F.Paste")
			(net "GND")
		)
		(pad "P51" smd circle
			(at 7.202932 -20.464526)
			(size 0.4318 0.4318)
			(layers "F.Cu" "F.Mask" "F.Paste")
			(net "GND")
		)
		(pad "P53" smd circle
			(at 8.919972 -20.464526)
			(size 0.4318 0.4318)
			(layers "F.Cu" "F.Mask" "F.Paste")
			(net "GND")
		)
		(pad "P55" smd circle
			(at 10.637012 -20.464526)
			(size 0.4318 0.4318)
			(layers "F.Cu" "F.Mask" "F.Paste")
			(net "GND")
		)
		(pad "P57" smd circle
			(at 12.354052 -20.464526)
			(size 0.4318 0.4318)
			(layers "F.Cu" "F.Mask" "F.Paste")
			(net "GND")
		)
		(pad "P59" smd circle
			(at 14.071092 -20.464526)
			(size 0.4318 0.4318)
			(layers "F.Cu" "F.Mask" "F.Paste")
			(net "GND")
		)
		(pad "P61" smd circle
			(at 15.787878 -20.464526)
			(size 0.4318 0.4318)
			(layers "F.Cu" "F.Mask" "F.Paste")
			(net "GND")
		)
		(pad "P63" smd circle
			(at 17.504918 -20.464526)
			(size 0.4318 0.4318)
			(layers "F.Cu" "F.Mask" "F.Paste")
			(net "GND")
		)
		(pad "P65" smd circle
			(at 19.221958 -20.464526)
			(size 0.4318 0.4318)
			(layers "F.Cu" "F.Mask" "F.Paste")
			(net "TP_CPU1_RSVD_265")
		)
		(pad "P67" smd circle
			(at 20.938998 -20.464526)
			(size 0.4318 0.4318)
			(layers "F.Cu" "F.Mask" "F.Paste")
			(net "GND")
		)
		(pad "P69" smd circle
			(at 22.656038 -20.464526)
			(size 0.4318 0.4318)
			(layers "F.Cu" "F.Mask" "F.Paste")
			(net "GND")
		)
		(pad "P71" smd circle
			(at 24.373078 -20.464526)
			(size 0.4318 0.4318)
			(layers "F.Cu" "F.Mask" "F.Paste")
			(net "GND")
		)
		(pad "P73" smd circle
			(at 26.090118 -20.464526)
			(size 0.4318 0.4318)
			(layers "F.Cu" "F.Mask" "F.Paste")
			(net "M_G_DQ<27>")
		)
		(pad "P75" smd circle
			(at 27.806904 -20.464526)
			(size 0.4318 0.4318)
			(layers "F.Cu" "F.Mask" "F.Paste")
			(net "M_G_DQS_DP<3>")
		)
		(pad "P77" smd circle
			(at 29.523944 -20.464526)
			(size 0.4318 0.4318)
			(layers "F.Cu" "F.Mask" "F.Paste")
			(net "M_G_DQ<29>")
		)
		(pad "P79" smd circle
			(at 31.240984 -20.464526)
			(size 0.4318 0.4318)
			(layers "F.Cu" "F.Mask" "F.Paste")
			(net "M_G_DQS_DN<2>")
		)
		(pad "P81" smd circle
			(at 32.958024 -20.464526)
			(size 0.4318 0.4318)
			(layers "F.Cu" "F.Mask" "F.Paste")
			(net "GND")
		)
		(pad "P83" smd circle
			(at 34.675064 -20.464526)
			(size 0.4318 0.4318)
			(layers "F.Cu" "F.Mask" "F.Paste")
			(net "GND")
		)
		(pad "P85" smd circle
			(at 36.392104 -20.464526)
			(size 0.4318 0.4318)
			(layers "F.Cu" "F.Mask" "F.Paste")
			(net "M_G_DQS_DP<1>")
		)
		(pad "R2" smd circle
			(at -36.392104 -18.168874)
			(size 0.4318 0.4318)
			(layers "F.Cu" "F.Mask" "F.Paste")
			(net "GND")
		)
		(pad "R4" smd circle
			(at -34.675064 -18.168874)
			(size 0.4318 0.4318)
			(layers "F.Cu" "F.Mask" "F.Paste")
			(net "GND")
		)
		(pad "R6" smd circle
			(at -32.958024 -18.168874)
			(size 0.4318 0.4318)
			(layers "F.Cu" "F.Mask" "F.Paste")
			(net "UPI_CPU0_CPU1_P1P1_DN<0>")
		)
		(pad "R8" smd circle
			(at -31.240984 -18.168874)
			(size 0.4318 0.4318)
			(layers "F.Cu" "F.Mask" "F.Paste")
			(net "UPI_CPU0_CPU1_P1P1_DP<3>")
		)
		(pad "R10" smd circle
			(at -29.523944 -18.168874)
			(size 0.4318 0.4318)
			(layers "F.Cu" "F.Mask" "F.Paste")
			(net "UPI_CPU0_CPU1_P1P1_DN<5>")
		)
		(pad "R12" smd circle
			(at -27.806904 -18.168874)
			(size 0.4318 0.4318)
			(layers "F.Cu" "F.Mask" "F.Paste")
			(net "UPI_CPU0_CPU1_P1P1_DN<9>")
		)
		(pad "R14" smd circle
			(at -26.090118 -18.168874)
			(size 0.4318 0.4318)
			(layers "F.Cu" "F.Mask" "F.Paste")
			(net "GND")
		)
		(pad "R16" smd circle
			(at -24.373078 -18.168874)
			(size 0.4318 0.4318)
			(layers "F.Cu" "F.Mask" "F.Paste")
			(net "UPI_CPU0_CPU1_P1P1_DN<10>")
		)
		(pad "R18" smd circle
			(at -22.656038 -18.168874)
			(size 0.4318 0.4318)
			(layers "F.Cu" "F.Mask" "F.Paste")
			(net "GND")
		)
		(pad "R20" smd circle
			(at -20.938998 -18.168874)
			(size 0.4318 0.4318)
			(layers "F.Cu" "F.Mask" "F.Paste")
			(net "UPI_CPU0_CPU1_P1P1_DN<14>")
		)
		(pad "R22" smd circle
			(at -19.221958 -18.168874)
			(size 0.4318 0.4318)
			(layers "F.Cu" "F.Mask" "F.Paste")
			(net "GND")
		)
		(pad "R24" smd circle
			(at -17.504918 -18.168874)
			(size 0.4318 0.4318)
			(layers "F.Cu" "F.Mask" "F.Paste")
			(net "M_G_DQS_DP<7>")
		)
		(pad "R26" smd circle
			(at -15.787878 -18.168874)
			(size 0.4318 0.4318)
			(layers "F.Cu" "F.Mask" "F.Paste")
			(net "GND")
		)
		(pad "R28" smd circle
			(at -14.071092 -18.168874)
			(size 0.4318 0.4318)
			(layers "F.Cu" "F.Mask" "F.Paste")
			(net "GND")
		)
		(pad "R30" smd circle
			(at -12.354052 -18.168874)
			(size 0.4318 0.4318)
			(layers "F.Cu" "F.Mask" "F.Paste")
			(net "M_G_DQS_DN<6>")
		)
		(pad "R32" smd circle
			(at -10.637012 -18.168874)
			(size 0.4318 0.4318)
			(layers "F.Cu" "F.Mask" "F.Paste")
			(net "GND")
		)
		(pad "R34" smd circle
			(at -8.919972 -18.168874)
			(size 0.4318 0.4318)
			(layers "F.Cu" "F.Mask" "F.Paste")
			(net "GND")
		)
		(pad "R36" smd circle
			(at -7.202932 -18.168874)
			(size 0.4318 0.4318)
			(layers "F.Cu" "F.Mask" "F.Paste")
			(net "M_G_DQS_DN<5>")
		)
		(pad "R38" smd circle
			(at -5.485892 -18.168874)
			(size 0.4318 0.4318)
			(layers "F.Cu" "F.Mask" "F.Paste")
			(net "GND")
		)
		(pad "R40" smd circle
			(at -3.769106 -18.168874)
			(size 0.4318 0.4318)
			(layers "F.Cu" "F.Mask" "F.Paste")
			(net "GND")
		)
		(pad "R42" smd circle
			(at -2.052066 -18.168874)
			(size 0.4318 0.4318)
			(layers "F.Cu" "F.Mask" "F.Paste")
			(net "M_H_DQS_DP<4>")
		)
		(pad "R46" smd circle
			(at 2.910586 -19.968972)
			(size 0.4318 0.4318)
			(layers "F.Cu" "F.Mask" "F.Paste")
			(net "M_H_CS_N<7>")
		)
		(pad "R48" smd circle
			(at 4.627626 -19.968972)
			(size 0.4318 0.4318)
			(layers "F.Cu" "F.Mask" "F.Paste")
			(net "M_H_ODT<1>")
		)
		(pad "R50" smd circle
			(at 6.344412 -19.968972)
			(size 0.4318 0.4318)
			(layers "F.Cu" "F.Mask" "F.Paste")
			(net "M_H_CS_N<1>")
		)
		(pad "R52" smd circle
			(at 8.061452 -19.968972)
			(size 0.4318 0.4318)
			(layers "F.Cu" "F.Mask" "F.Paste")
			(net "M_H_MA<16>")
		)
		(pad "R54" smd circle
			(at 9.778492 -19.968972)
			(size 0.4318 0.4318)
			(layers "F.Cu" "F.Mask" "F.Paste")
			(net "M_H_CLK_DN<1>")
		)
		(pad "R56" smd circle
			(at 11.495532 -19.968972)
			(size 0.4318 0.4318)
			(layers "F.Cu" "F.Mask" "F.Paste")
			(net "M_H_CLK_DN<3>")
		)
		(pad "R58" smd circle
			(at 13.212572 -19.968972)
			(size 0.4318 0.4318)
			(layers "F.Cu" "F.Mask" "F.Paste")
			(net "M_H_MA<5>")
		)
		(pad "R60" smd circle
			(at 14.929612 -19.968972)
			(size 0.4318 0.4318)
			(layers "F.Cu" "F.Mask" "F.Paste")
			(net "M_H_MA<11>")
		)
		(pad "R62" smd circle
			(at 16.646398 -19.968972)
			(size 0.4318 0.4318)
			(layers "F.Cu" "F.Mask" "F.Paste")
			(net "TP_CPU1_RSVD_264")
		)
		(pad "R64" smd circle
			(at 18.363438 -19.968972)
			(size 0.4318 0.4318)
			(layers "F.Cu" "F.Mask" "F.Paste")
			(net "M_H_CKE<1>")
		)
		(pad "R66" smd circle
			(at 20.080478 -19.968972)
			(size 0.4318 0.4318)
			(layers "F.Cu" "F.Mask" "F.Paste")
			(net "TP_CPU1_RSVD_263")
		)
		(pad "R68" smd circle
			(at 21.797518 -19.968972)
			(size 0.4318 0.4318)
			(layers "F.Cu" "F.Mask" "F.Paste")
			(net "GND")
		)
		(pad "R70" smd circle
			(at 23.514558 -19.968972)
			(size 0.4318 0.4318)
			(layers "F.Cu" "F.Mask" "F.Paste")
			(net "M_J_DQ<18>")
		)
		(pad "R72" smd circle
			(at 25.231598 -19.968972)
			(size 0.4318 0.4318)
			(layers "F.Cu" "F.Mask" "F.Paste")
			(net "GND")
		)
		(pad "R74" smd circle
			(at 26.948384 -19.968972)
			(size 0.4318 0.4318)
			(layers "F.Cu" "F.Mask" "F.Paste")
			(net "M_G_DQ<31>")
		)
		(pad "R76" smd circle
			(at 28.665424 -19.968972)
			(size 0.4318 0.4318)
			(layers "F.Cu" "F.Mask" "F.Paste")
			(net "M_G_DQ<25>")
		)
		(pad "R78" smd circle
			(at 30.382464 -19.968972)
			(size 0.4318 0.4318)
			(layers "F.Cu" "F.Mask" "F.Paste")
			(net "GND")
		)
		(pad "R80" smd circle
			(at 32.099504 -19.968972)
			(size 0.4318 0.4318)
			(layers "F.Cu" "F.Mask" "F.Paste")
			(net "M_G_DQS_DP<2>")
		)
		(pad "R82" smd circle
			(at 33.816544 -19.968972)
			(size 0.4318 0.4318)
			(layers "F.Cu" "F.Mask" "F.Paste")
			(net "M_G_DQ<22>")
		)
		(pad "R84" smd circle
			(at 35.533584 -19.968972)
			(size 0.4318 0.4318)
			(layers "F.Cu" "F.Mask" "F.Paste")
			(net "M_G_DQS_DN<1>")
		)
		(pad "R86" smd custom
			(at 37.250624 -19.968972 270)
			(size 0.10795 0.10795)
			(layers "F.Cu" "F.Mask" "F.Paste")
			(net "GND")
			(options
				(clearance outline)
				(anchor circle)
			)
			(primitives
				(gr_poly
					(pts
						(arc
							(start 0.2159 -0.0381)
							(mid 0 -0.254)
							(end -0.2159 -0.0381)
						)
						(arc
							(start -0.2159 0.0381)
							(mid 0 0.254)
							(end 0.2159 0.0381)
						)
					)
					(width 0)
					(fill yes)
				)
			)
		)
		(pad "T1" smd custom
			(at -37.250624 -17.673574 90)
			(size 0.10795 0.10795)
			(layers "F.Cu" "F.Mask" "F.Paste")
			(net "UPI_CPU1_CPU0_P0P0_DN<1>")
			(options
				(clearance outline)
				(anchor circle)
			)
			(primitives
				(gr_poly
					(pts
						(arc
							(start 0.2159 -0.0381)
							(mid 0 -0.254)
							(end -0.2159 -0.0381)
						)
						(arc
							(start -0.2159 0.0381)
							(mid 0 0.254)
							(end 0.2159 0.0381)
						)
					)
					(width 0)
					(fill yes)
				)
			)
		)
		(pad "T3" smd circle
			(at -35.533584 -17.673574)
			(size 0.4318 0.4318)
			(layers "F.Cu" "F.Mask" "F.Paste")
			(net "PVCCIO_CPU1")
		)
		(pad "T5" smd circle
			(at -33.816544 -17.673574)
			(size 0.4318 0.4318)
			(layers "F.Cu" "F.Mask" "F.Paste")
			(net "UPI_CPU0_CPU1_P1P1_DP<0>")
		)
		(pad "T7" smd circle
			(at -32.099504 -17.673574)
			(size 0.4318 0.4318)
			(layers "F.Cu" "F.Mask" "F.Paste")
			(net "UPI_CPU0_CPU1_P1P1_DP<1>")
		)
		(pad "T9" smd circle
			(at -30.382464 -17.673574)
			(size 0.4318 0.4318)
			(layers "F.Cu" "F.Mask" "F.Paste")
			(net "UPI_CPU0_CPU1_P1P1_DN<3>")
		)
		(pad "T11" smd circle
			(at -28.665424 -17.673574)
			(size 0.4318 0.4318)
			(layers "F.Cu" "F.Mask" "F.Paste")
			(net "UPI_CPU0_CPU1_P1P1_DP<6>")
		)
		(pad "T13" smd circle
			(at -26.948384 -17.673574)
			(size 0.4318 0.4318)
			(layers "F.Cu" "F.Mask" "F.Paste")
			(net "GND")
		)
		(pad "T15" smd circle
			(at -25.231598 -17.673574)
			(size 0.4318 0.4318)
			(layers "F.Cu" "F.Mask" "F.Paste")
			(net "UPI_CPU0_CPU1_P1P1_DP<10>")
		)
		(pad "T17" smd circle
			(at -23.514558 -17.673574)
			(size 0.4318 0.4318)
			(layers "F.Cu" "F.Mask" "F.Paste")
			(net "GND")
		)
		(pad "T19" smd circle
			(at -21.797518 -17.673574)
			(size 0.4318 0.4318)
			(layers "F.Cu" "F.Mask" "F.Paste")
			(net "UPI_CPU0_CPU1_P1P1_DP<15>")
		)
		(pad "T21" smd circle
			(at -20.080478 -17.673574)
			(size 0.4318 0.4318)
			(layers "F.Cu" "F.Mask" "F.Paste")
			(net "UPI_CPU0_CPU1_P1P1_DP<16>")
		)
		(pad "T23" smd circle
			(at -18.363438 -17.673574)
			(size 0.4318 0.4318)
			(layers "F.Cu" "F.Mask" "F.Paste")
			(net "M_G_DQ<59>")
		)
		(pad "T25" smd circle
			(at -16.646398 -17.673574)
			(size 0.4318 0.4318)
			(layers "F.Cu" "F.Mask" "F.Paste")
			(net "GND")
		)
		(pad "T27" smd circle
			(at -14.929612 -17.673574)
			(size 0.4318 0.4318)
			(layers "F.Cu" "F.Mask" "F.Paste")
			(net "M_H_DQS_DN<16>")
		)
		(pad "T29" smd circle
			(at -13.212572 -17.673574)
			(size 0.4318 0.4318)
			(layers "F.Cu" "F.Mask" "F.Paste")
			(net "GND")
		)
		(pad "T31" smd circle
			(at -11.495532 -17.673574)
			(size 0.4318 0.4318)
			(layers "F.Cu" "F.Mask" "F.Paste")
			(net "GND")
		)
		(pad "T33" smd circle
			(at -9.778492 -17.673574)
			(size 0.4318 0.4318)
			(layers "F.Cu" "F.Mask" "F.Paste")
			(net "M_J_DQS_DN<14>")
		)
		(pad "T35" smd circle
			(at -8.061452 -17.673574)
			(size 0.4318 0.4318)
			(layers "F.Cu" "F.Mask" "F.Paste")
			(net "GND")
		)
		(pad "T37" smd circle
			(at -6.344412 -17.673574)
			(size 0.4318 0.4318)
			(layers "F.Cu" "F.Mask" "F.Paste")
			(net "GND")
		)
		(pad "T39" smd circle
			(at -4.627626 -17.673574)
			(size 0.4318 0.4318)
			(layers "F.Cu" "F.Mask" "F.Paste")
			(net "M_J_DQS_DN<13>")
		)
		(pad "T41" smd circle
			(at -2.910586 -17.673574)
			(size 0.4318 0.4318)
			(layers "F.Cu" "F.Mask" "F.Paste")
			(net "GND")
		)
		(pad "T43" smd circle
			(at -1.193546 -17.673574)
			(size 0.4318 0.4318)
			(layers "F.Cu" "F.Mask" "F.Paste")
			(net "M_H_DQ<37>")
		)
		(pad "T45" smd circle
			(at 2.052066 -19.473926)
			(size 0.508 0.508)
			(layers "F.Cu" "F.Mask" "F.Paste")
			(net "M_J_CS_N<6>")
		)
		(pad "T47" smd circle
			(at 3.769106 -19.473926)
			(size 0.4318 0.4318)
			(layers "F.Cu" "F.Mask" "F.Paste")
			(net "M_H_ODT<3>")
		)
		(pad "T49" smd circle
			(at 5.485892 -19.473926)
			(size 0.4318 0.4318)
			(layers "F.Cu" "F.Mask" "F.Paste")
			(net "M_H_CS_N<5>")
		)
		(pad "T51" smd circle
			(at 7.202932 -19.473926)
			(size 0.4318 0.4318)
			(layers "F.Cu" "F.Mask" "F.Paste")
			(net "M_H_MA<14>")
		)
		(pad "T53" smd circle
			(at 8.919972 -19.473926)
			(size 0.4318 0.4318)
			(layers "F.Cu" "F.Mask" "F.Paste")
			(net "M_H_BA<0>")
		)
		(pad "T55" smd circle
			(at 10.637012 -19.473926)
			(size 0.4318 0.4318)
			(layers "F.Cu" "F.Mask" "F.Paste")
			(net "M_H_CLK_DP<1>")
		)
		(pad "T57" smd circle
			(at 12.354052 -19.473926)
			(size 0.4318 0.4318)
			(layers "F.Cu" "F.Mask" "F.Paste")
			(net "M_H_CLK_DP<3>")
		)
		(pad "T59" smd circle
			(at 14.071092 -19.473926)
			(size 0.4318 0.4318)
			(layers "F.Cu" "F.Mask" "F.Paste")
			(net "M_H_MA<6>")
		)
		(pad "T61" smd circle
			(at 15.787878 -19.473926)
			(size 0.4318 0.4318)
			(layers "F.Cu" "F.Mask" "F.Paste")
			(net "M_H_MA<12>")
		)
		(pad "T63" smd circle
			(at 17.504918 -19.473926)
			(size 0.4318 0.4318)
			(layers "F.Cu" "F.Mask" "F.Paste")
			(net "M_H_ACT_N")
		)
		(pad "T65" smd circle
			(at 19.221958 -19.473926)
			(size 0.4318 0.4318)
			(layers "F.Cu" "F.Mask" "F.Paste")
			(net "GND")
		)
		(pad "T67" smd circle
			(at 20.938998 -19.473926)
			(size 0.4318 0.4318)
			(layers "F.Cu" "F.Mask" "F.Paste")
			(net "TP_CPU1_RSVD_262")
		)
		(pad "T69" smd circle
			(at 22.656038 -19.473926)
			(size 0.4318 0.4318)
			(layers "F.Cu" "F.Mask" "F.Paste")
			(net "M_J_DQ<19>")
		)
		(pad "T71" smd circle
			(at 24.373078 -19.473926)
			(size 0.4318 0.4318)
			(layers "F.Cu" "F.Mask" "F.Paste")
			(net "M_J_DQ<22>")
		)
		(pad "T73" smd circle
			(at 26.090118 -19.473926)
			(size 0.4318 0.4318)
			(layers "F.Cu" "F.Mask" "F.Paste")
			(net "GND")
		)
		(pad "T75" smd circle
			(at 27.806904 -19.473926)
			(size 0.4318 0.4318)
			(layers "F.Cu" "F.Mask" "F.Paste")
			(net "M_G_DQS_DN<3>")
		)
		(pad "T77" smd circle
			(at 29.523944 -19.473926)
			(size 0.4318 0.4318)
			(layers "F.Cu" "F.Mask" "F.Paste")
			(net "GND")
		)
		(pad "T79" smd circle
			(at 31.240984 -19.473926)
			(size 0.4318 0.4318)
			(layers "F.Cu" "F.Mask" "F.Paste")
			(net "M_G_DQ<17>")
		)
		(pad "T81" smd circle
			(at 32.958024 -19.473926)
			(size 0.4318 0.4318)
			(layers "F.Cu" "F.Mask" "F.Paste")
			(net "M_G_DQS_DP<11>")
		)
		(pad "T83" smd circle
			(at 34.675064 -19.473926)
			(size 0.4318 0.4318)
			(layers "F.Cu" "F.Mask" "F.Paste")
			(net "GND")
		)
		(pad "T85" smd circle
			(at 36.392104 -19.473926)
			(size 0.4318 0.4318)
			(layers "F.Cu" "F.Mask" "F.Paste")
			(net "GND")
		)
		(pad "U2" smd circle
			(at -36.392104 -17.178528)
			(size 0.4318 0.4318)
			(layers "F.Cu" "F.Mask" "F.Paste")
			(net "GND")
		)
		(pad "U4" smd circle
			(at -34.675064 -17.178528)
			(size 0.4318 0.4318)
			(layers "F.Cu" "F.Mask" "F.Paste")
			(net "GND")
		)
		(pad "U6" smd circle
			(at -32.958024 -17.178528)
			(size 0.4318 0.4318)
			(layers "F.Cu" "F.Mask" "F.Paste")
			(net "GND")
		)
		(pad "U8" smd circle
			(at -31.240984 -17.178528)
			(size 0.4318 0.4318)
			(layers "F.Cu" "F.Mask" "F.Paste")
			(net "UPI_CPU0_CPU1_P1P1_DP<2>")
		)
		(pad "U10" smd circle
			(at -29.523944 -17.178528)
			(size 0.4318 0.4318)
			(layers "F.Cu" "F.Mask" "F.Paste")
			(net "UPI_CPU0_CPU1_P1P1_DP<5>")
		)
	)
)
